# T6G (Grand Teton) — schematic netlist excerpt (pin names and nets, part order shuffled) for the footprints in the layout excerpt that follows; sources: Cadence DE-HDL packaged netlist, KiCad conversion of 04192023_DAF0TMB3IC0_F0TG_MB_C_brd_V02_OCP.brd

C6587  Q_CAP_DIFFBUS  DIFF BUS_0.22UF 6.3V 20% X6S  pkg C0201  page 297 : \1\ = P5E_CPU0_P2_TX_BUF_C_DP<11> ; \2\ = P5E_CPU0_P2_TX_BUF_DP<11>
R1287  Q_RES  4.7K 5% CHIP  pkg 0402LF  page 83 : A = FM_P0_PCC0_N ; B = PVDD18_S5_P0
C1767  Q_CAP  10UF 16V 10% X6S  pkg C0805  page 257 : A = MAX11617_VREF ; B = GND

(kicad_pcb
	(version 20260206)
	(generator "pcbnew")
	(generator_version "10.0")
	(general
		(thickness 1.6)
		(legacy_teardrops no)
	)
	(paper "A4")
	(title_block
		(title "04192023_DAF0TMB3IC0_F0TG_MB_C_brd_V02_OCP.brd")
		(comment 1 "Grand Teton / footprints 3693-3695 of 8354")
	)
	(layers
		(0 "F.Cu" signal "TOP")
		(4 "In1.Cu" signal "GND")
		(6 "In2.Cu" signal "IN1")
		(8 "In3.Cu" signal "GND1")
		(10 "In4.Cu" signal "IN2")
		(12 "In5.Cu" signal "GND2")
		(14 "In6.Cu" signal "IN3")
		(16 "In7.Cu" signal "GND3")
		(18 "In8.Cu" signal "VCC")
		(20 "In9.Cu" signal "VCC1")
		(22 "In10.Cu" signal "GND4")
		(24 "In11.Cu" signal "IN4")
		(26 "In12.Cu" signal "GND5")
		(28 "In13.Cu" signal "IN5")
		(30 "In14.Cu" signal "GND6")
		(32 "In15.Cu" signal "IN6")
		(34 "In16.Cu" signal "GND7")
		(2 "B.Cu" signal "BOTTOM")
		(9 "F.Adhes" user "F.Adhesive")
		(11 "B.Adhes" user "B.Adhesive")
		(13 "F.Paste" user "Package Geometry/Pastemask Top")
		(15 "B.Paste" user "Package Geometry/Pastemask Bottom")
		(5 "F.SilkS" user "Ref Des/Silkscreen Top")
		(7 "B.SilkS" user "Ref Des/Silkscreen Bottom")
		(1 "F.Mask" user "Board Geometry/Soldermask Top")
		(3 "B.Mask" user "Board Geometry/Soldermask Bottom")
		(17 "Dwgs.User" user "User.Drawings")
		(19 "Cmts.User" user "User.Comments")
		(21 "Eco1.User" user "User.Eco1")
		(23 "Eco2.User" user "User.Eco2")
		(25 "Edge.Cuts" user "Board Geometry/Outline")
		(27 "Margin" user)
		(31 "F.CrtYd" user "Package Geometry/Place Bound Top")
		(29 "B.CrtYd" user "Package Geometry/Place Bound Bottom")
		(35 "F.Fab" user "Ref Des/Assembly Top")
		(33 "B.Fab" user "Ref Des/Assembly Bottom")
	)
	(footprint ""
		(layer "F.Cu")
		(at 310.056022 -37.017706 180)
		(property "Reference" "C1767"
			(at 0 0 180)
			(layer "F.SilkS")
			(hide yes)
			(effects
				(font
					(size 1.27 1.27)
				)
			)
		)
		(property "Value" ""
			(at 0 0 180)
			(layer "F.Fab")
			(effects
				(font
					(size 1.27 1.27)
				)
			)
		)
		(duplicate_pad_numbers_are_jumpers no)
		(fp_line
			(start 1.524 0.762)
			(end -1.524 0.762)
			(stroke
				(width 0.1524)
				(type default)
			)
			(layer "F.SilkS")
		)
		(fp_line
			(start 1.524 -0.762)
			(end 1.524 0.762)
			(stroke
				(width 0.1524)
				(type default)
			)
			(layer "F.SilkS")
		)
		(fp_line
			(start -1.524 0.762)
			(end -1.524 -0.762)
			(stroke
				(width 0.1524)
				(type default)
			)
			(layer "F.SilkS")
		)
		(fp_line
			(start -1.524 -0.762)
			(end 1.524 -0.762)
			(stroke
				(width 0.1524)
				(type default)
			)
			(layer "F.SilkS")
		)
		(fp_line
			(start 1.1049 0.724916)
			(end 1.1049 -0.724916)
			(stroke
				(width 0.1)
				(type default)
			)
			(layer "F.Fab")
		)
		(fp_line
			(start 1.1049 -0.724916)
			(end -1.1049 -0.724916)
			(stroke
				(width 0.1)
				(type default)
			)
			(layer "F.Fab")
		)
		(fp_line
			(start -1.1049 0.724916)
			(end 1.1049 0.724916)
			(stroke
				(width 0.1)
				(type default)
			)
			(layer "F.Fab")
		)
		(fp_line
			(start -1.1049 -0.724916)
			(end -1.1049 0.724916)
			(stroke
				(width 0.1)
				(type default)
			)
			(layer "F.Fab")
		)
		(pad "1" smd rect
			(at -0.889 0)
			(size 1.016 1.27)
			(layers "F.Cu" "F.Mask" "F.Paste")
			(net "MAX11617_VREF")
		)
		(pad "2" smd rect
			(at 0.889 0)
			(size 1.016 1.27)
			(layers "F.Cu" "F.Mask" "F.Paste")
			(net "GND")
		)
	)
	(footprint ""
		(layer "F.Cu")
		(at 405.478742 -416.899344 -90)
		(property "Reference" "C6587"
			(at 0 0 270)
			(layer "F.SilkS")
			(hide yes)
			(effects
				(font
					(size 1.27 1.27)
				)
			)
		)
		(property "Value" ""
			(at 0 0 270)
			(layer "F.Fab")
			(effects
				(font
					(size 1.27 1.27)
				)
			)
		)
		(duplicate_pad_numbers_are_jumpers no)
		(fp_line
			(start -0.299974 0.150114)
			(end -0.299974 -0.150114)
			(stroke
				(width 0.1)
				(type default)
			)
			(layer "F.Fab")
		)
		(fp_line
			(start 0.299974 0.150114)
			(end -0.299974 0.150114)
			(stroke
				(width 0.1)
				(type default)
			)
			(layer "F.Fab")
		)
		(fp_line
			(start -0.299974 -0.150114)
			(end 0.299974 -0.150114)
			(stroke
				(width 0.1)
				(type default)
			)
			(layer "F.Fab")
		)
		(fp_line
			(start 0.299974 -0.150114)
			(end 0.299974 0.150114)
			(stroke
				(width 0.1)
				(type default)
			)
			(layer "F.Fab")
		)
		(pad "1" smd rect
			(at -0.2667 0 270)
			(size 0.3048 0.381)
			(layers "F.Cu" "F.Mask" "F.Paste")
			(net "P5E_CPU0_P2_TX_BUF_C_DP<11>")
		)
		(pad "2" smd rect
			(at 0.2667 0 270)
			(size 0.3048 0.381)
			(layers "F.Cu" "F.Mask" "F.Paste")
			(net "P5E_CPU0_P2_TX_BUF_DP<11>")
		)
	)
	(footprint ""
		(layer "F.Cu")
		(at 183.007 -140.172948 90)
		(property "Reference" "R1287"
			(at 0 0 90)
			(layer "F.SilkS")
			(hide yes)
			(effects
				(font
					(size 1.27 1.27)
				)
			)
		)
		(property "Value" ""
			(at 0 0 90)
			(layer "F.Fab")
			(effects
				(font
					(size 1.27 1.27)
				)
			)
		)
		(duplicate_pad_numbers_are_jumpers no)
		(fp_line
			(start 0.7874 -0.4064)
			(end 0.7874 0.4064)
			(stroke
				(width 0.1524)
				(type default)
			)
			(layer "F.SilkS")
		)
		(fp_line
			(start -0.7874 -0.4064)
			(end 0.7874 -0.4064)
			(stroke
				(width 0.1524)
				(type default)
			)
			(layer "F.SilkS")
		)
		(fp_line
			(start 0.7874 0.4064)
			(end -0.7874 0.4064)
			(stroke
				(width 0.1524)
				(type default)
			)
			(layer "F.SilkS")
		)
		(fp_line
			(start -0.7874 0.4064)
			(end -0.7874 -0.4064)
			(stroke
				(width 0.1524)
				(type default)
			)
			(layer "F.SilkS")
		)
		(fp_line
			(start -0.12065 -0.305054)
			(end -0.12065 -0.2794)
			(stroke
				(width 0.1)
				(type default)
			)
			(layer "F.Fab")
		)
		(fp_line
			(start -0.67945 -0.305054)
			(end -0.12065 -0.305054)
			(stroke
				(width 0.1)
				(type default)
			)
			(layer "F.Fab")
		)
		(fp_line
			(start 0.67945 -0.3048)
			(end 0.67945 0.3048)
			(stroke
				(width 0.1)
				(type default)
			)
			(layer "F.Fab")
		)
		(fp_line
			(start 0.12065 -0.3048)
			(end 0.67945 -0.3048)
			(stroke
				(width 0.1)
				(type default)
			)
			(layer "F.Fab")
		)
		(fp_line
			(start 0.12065 -0.2794)
			(end 0.12065 -0.3048)
			(stroke
				(width 0.1)
				(type default)
			)
			(layer "F.Fab")
		)
		(fp_line
			(start -0.12065 -0.2794)
			(end 0.12065 -0.2794)
			(stroke
				(width 0.1)
				(type default)
			)
			(layer "F.Fab")
		)
		(fp_line
			(start 0.120396 0.2794)
			(end -0.12065 0.2794)
			(stroke
				(width 0.1)
				(type default)
			)
			(layer "F.Fab")
		)
		(fp_line
			(start -0.12065 0.2794)
			(end -0.12065 0.3048)
			(stroke
				(width 0.1)
				(type default)
			)
			(layer "F.Fab")
		)
		(fp_line
			(start 0.67945 0.3048)
			(end 0.120396 0.3048)
			(stroke
				(width 0.1)
				(type default)
			)
			(layer "F.Fab")
		)
		(fp_line
			(start 0.120396 0.3048)
			(end 0.120396 0.2794)
			(stroke
				(width 0.1)
				(type default)
			)
			(layer "F.Fab")
		)
		(fp_line
			(start -0.12065 0.3048)
			(end -0.67945 0.3048)
			(stroke
				(width 0.1)
				(type default)
			)
			(layer "F.Fab")
		)
		(fp_line
			(start -0.67945 0.3048)
			(end -0.67945 -0.305054)
			(stroke
				(width 0.1)
				(type default)
			)
			(layer "F.Fab")
		)
		(pad "1" smd circle
			(at -0.40005 0 90)
			(size 0 0)
			(layers "F.Cu" "F.Mask" "F.Paste")
			(net "FM_P0_PCC0_N")
		)
		(pad "2" smd circle
			(at 0.40005 0 90)
			(size 0 0)
			(layers "F.Cu" "F.Mask" "F.Paste")
			(net "PVDD18_S5_P0")
		)
	)
)
